# Lightning_M.2_SI constraints.xls — Net Rule by Layer (si-constraints)
| Project Name: 15750-1 |  |  |  |  |  |  |  |  |  |  |  |  |  |  |  |  |  |
| Project Path: C:\Users\<user>\Desktop\OCP\M.2\15750-1_20161229-1104.db |  |  |  |  |  |  |  |  |  |  |  |  |  |  |  |  |  |
| Net Name | Group Name | Type | Layer | T_W(X) | P-P | P-V | P-T | V-V | V-T | T_T(Y) | P-F | V-F | T-F | F-F | T_T(Z) | Ohm | Ref Layer |
| SSD_A1_SMB_OE | 50OHM_12S | BUS | 1 | 4.75 | 5 | 10 | 5 | 14 | 12 | 12 | 12 | 12 | 12 | 12 |  | 50 Ohms | TOP=L2:L3=L2/L4:L6=L5/L7:BOTTOM=L7 |
| SSD_B1_SMB_OE | 50OHM_12S | BUS | 1 | 4.75 | 5 | 10 | 5 | 14 | 12 | 12 | 12 | 12 | 12 | 12 |  | 50 Ohms | TOP=L2:L3=L2/L4:L6=L5/L7:BOTTOM=L7 |
| Z50_DEV_RST# | 50OHM_12S | BUS | 1 | 4.75 | 5 | 10 | 5 | 14 | 12 | 12 | 12 | 12 | 12 | 12 |  | 50 Ohms | TOP=L2:L3=L2/L4:L6=L5/L7:BOTTOM=L7 |
| Z50_SMB_SWITCH_ADDRESS_A0 | 50OHM_12S | BUS | 1 | 4.75 | 5 | 10 | 5 | 14 | 12 | 12 | 12 | 12 | 12 | 12 |  | 50 Ohms | TOP=L2:L3=L2/L4:L6=L5/L7:BOTTOM=L7 |
| Z50_SMB_SWITCH_ADDRESS_A1 | 50OHM_12S | BUS | 1 | 4.75 | 5 | 10 | 5 | 14 | 12 | 12 | 12 | 12 | 12 | 12 |  | 50 Ohms | TOP=L2:L3=L2/L4:L6=L5/L7:BOTTOM=L7 |
| Z50_SSD_A_ACT# | 50OHM_12S | BUS | 1 | 4.75 | 5 | 10 | 5 | 14 | 12 | 12 | 12 | 12 | 12 | 12 |  | 50 Ohms | TOP=L2:L3=L2/L4:L6=L5/L7:BOTTOM=L7 |
| Z50_SSD_A_PRESENT_R# | 50OHM_12S | BUS | 1 | 4.75 | 5 | 10 | 5 | 14 | 12 | 12 | 12 | 12 | 12 | 12 |  | 50 Ohms | TOP=L2:L3=L2/L4:L6=L5/L7:BOTTOM=L7 |
| Z50_SSD_A_PRSNT# | 50OHM_12S | BUS | 1 | 4.75 | 5 | 10 | 5 | 14 | 12 | 12 | 12 | 12 | 12 | 12 |  | 50 Ohms | TOP=L2:L3=L2/L4:L6=L5/L7:BOTTOM=L7 |
| Z50_SSD_A_R_ACT# | 50OHM_12S | BUS | 1 | 4.75 | 5 | 10 | 5 | 14 | 12 | 12 | 12 | 12 | 12 | 12 |  | 50 Ohms | TOP=L2:L3=L2/L4:L6=L5/L7:BOTTOM=L7 |
| Z50_SSD_A1_ALERT# | 50OHM_12S | BUS | 1 | 4.75 | 5 | 10 | 5 | 14 | 12 | 12 | 12 | 12 | 12 | 12 |  | 50 Ohms | TOP=L2:L3=L2/L4:L6=L5/L7:BOTTOM=L7 |
| Z50_SSD_A1_CLKREQ# | 50OHM_12S | BUS | 1 | 4.75 | 5 | 10 | 5 | 14 | 12 | 12 | 12 | 12 | 12 | 12 |  | 50 Ohms | TOP=L2:L3=L2/L4:L6=L5/L7:BOTTOM=L7 |
| Z50_SSD_ACT# | 50OHM_12S | BUS | 1 | 4.75 | 5 | 10 | 5 | 14 | 12 | 12 | 12 | 12 | 12 | 12 |  | 50 Ohms | TOP=L2:L3=L2/L4:L6=L5/L7:BOTTOM=L7 |
| Z50_SSD_B_ACT# | 50OHM_12S | BUS | 1 | 4.75 | 5 | 10 | 5 | 14 | 12 | 12 | 12 | 12 | 12 | 12 |  | 50 Ohms | TOP=L2:L3=L2/L4:L6=L5/L7:BOTTOM=L7 |
| Z50_SSD_B_PRESENT_R# | 50OHM_12S | BUS | 1 | 4.75 | 5 | 10 | 5 | 14 | 12 | 12 | 12 | 12 | 12 | 12 |  | 50 Ohms | TOP=L2:L3=L2/L4:L6=L5/L7:BOTTOM=L7 |
| Z50_SSD_B_PRSNT# | 50OHM_12S | BUS | 1 | 4.75 | 5 | 10 | 5 | 14 | 12 | 12 | 12 | 12 | 12 | 12 |  | 50 Ohms | TOP=L2:L3=L2/L4:L6=L5/L7:BOTTOM=L7 |
| Z50_SSD_B_R_ACT# | 50OHM_12S | BUS | 1 | 4.75 | 5 | 10 | 5 | 14 | 12 | 12 | 12 | 12 | 12 | 12 |  | 50 Ohms | TOP=L2:L3=L2/L4:L6=L5/L7:BOTTOM=L7 |
| Z50_SSD_B1_ALERT# | 50OHM_12S | BUS | 1 | 4.75 | 5 | 10 | 5 | 14 | 12 | 12 | 12 | 12 | 12 | 12 |  | 50 Ohms | TOP=L2:L3=L2/L4:L6=L5/L7:BOTTOM=L7 |
| Z50_SSD_B1_CLKREQ# | 50OHM_12S | BUS | 1 | 4.75 | 5 | 10 | 5 | 14 | 12 | 12 | 12 | 12 | 12 | 12 |  | 50 Ohms | TOP=L2:L3=L2/L4:L6=L5/L7:BOTTOM=L7 |
| Z50_SSD_M2_PRSNT# | 50OHM_12S | BUS | 1 | 4.75 | 5 | 10 | 5 | 14 | 12 | 12 | 12 | 12 | 12 | 12 |  | 50 Ohms | TOP=L2:L3=L2/L4:L6=L5/L7:BOTTOM=L7 |
| Z50_TEMP_1_A0 | 50OHM_12S | BUS | 1 | 4.75 | 5 | 10 | 5 | 14 | 12 | 12 | 12 | 12 | 12 | 12 |  | 50 Ohms | TOP=L2:L3=L2/L4:L6=L5/L7:BOTTOM=L7 |
| Z50_TEMP_1_A1 | 50OHM_12S | BUS | 1 | 4.75 | 5 | 10 | 5 | 14 | 12 | 12 | 12 | 12 | 12 | 12 |  | 50 Ohms | TOP=L2:L3=L2/L4:L6=L5/L7:BOTTOM=L7 |
| Z50_TEMP_1_A2 | 50OHM_12S | BUS | 1 | 4.75 | 5 | 10 | 5 | 14 | 12 | 12 | 12 | 12 | 12 | 12 |  | 50 Ohms | TOP=L2:L3=L2/L4:L6=L5/L7:BOTTOM=L7 |
| Z50_TEMP_1_ALERT# | 50OHM_12S | BUS | 1 | 4.75 | 5 | 10 | 5 | 14 | 12 | 12 | 12 | 12 | 12 | 12 |  | 50 Ohms | TOP=L2:L3=L2/L4:L6=L5/L7:BOTTOM=L7 |
| SSD_A1_MFG_CLK_TP | 50OHM_15S | BUS | 1 | 4.75 | 5 | 10 | 5 | 14 | 12 | 15 | 12 | 12 | 12 | 12 |  | 50 Ohms-1 | TOP=L2:L3=L2/L4:L6=L5/L7:BOTTOM=L7 |
| SSD_A1_MFG_DATA_TP | 50OHM_15S | BUS | 1 | 4.75 | 5 | 10 | 5 | 14 | 12 | 15 | 12 | 12 | 12 | 12 |  | 50 Ohms-1 | TOP=L2:L3=L2/L4:L6=L5/L7:BOTTOM=L7 |
| SSD_B1_MFG_CLK_TP | 50OHM_15S | BUS | 1 | 4.75 | 5 | 10 | 5 | 14 | 12 | 15 | 12 | 12 | 12 | 12 |  | 50 Ohms-1 | TOP=L2:L3=L2/L4:L6=L5/L7:BOTTOM=L7 |
| SSD_B1_MFG_DATA_TP | 50OHM_15S | BUS | 1 | 4.75 | 5 | 10 | 5 | 14 | 12 | 15 | 12 | 12 | 12 | 12 |  | 50 Ohms-1 | TOP=L2:L3=L2/L4:L6=L5/L7:BOTTOM=L7 |
| Z50_SMB_CLK | 50OHM_15S | BUS | 1 | 4.75 | 5 | 10 | 5 | 14 | 12 | 15 | 12 | 12 | 12 | 12 |  | 50 Ohms-1 | TOP=L2:L3=L2/L4:L6=L5/L7:BOTTOM=L7 |
| Z50_SMB_DATA | 50OHM_15S | BUS | 1 | 4.75 | 5 | 10 | 5 | 14 | 12 | 15 | 12 | 12 | 12 | 12 |  | 50 Ohms-1 | TOP=L2:L3=L2/L4:L6=L5/L7:BOTTOM=L7 |
| Z50_SMB_SWITCH_RESET# | 50OHM_15S | BUS | 1 | 4.75 | 5 | 10 | 5 | 14 | 12 | 15 | 12 | 12 | 12 | 12 |  | 50 Ohms-1 | TOP=L2:L3=L2/L4:L6=L5/L7:BOTTOM=L7 |
| Z50_SSD_A1_SMB_CLK | 50OHM_15S | BUS | 1 | 4.75 | 5 | 10 | 5 | 14 | 12 | 15 | 12 | 12 | 12 | 12 |  | 50 Ohms-1 | TOP=L2:L3=L2/L4:L6=L5/L7:BOTTOM=L7 |
| Z50_SSD_A1_SMB_CLK_LL | 50OHM_15S | BUS | 1 | 4.75 | 5 | 10 | 5 | 14 | 12 | 15 | 12 | 12 | 12 | 12 |  | 50 Ohms-1 | TOP=L2:L3=L2/L4:L6=L5/L7:BOTTOM=L7 |
| Z50_SSD_A1_SMB_CLK_LR | 50OHM_15S | BUS | 1 | 4.75 | 5 | 10 | 5 | 14 | 12 | 15 | 12 | 12 | 12 | 12 |  | 50 Ohms-1 | TOP=L2:L3=L2/L4:L6=L5/L7:BOTTOM=L7 |
| Z50_SSD_A1_SMB_CLK_R | 50OHM_15S | BUS | 1 | 4.75 | 5 | 10 | 5 | 14 | 12 | 15 | 12 | 12 | 12 | 12 |  | 50 Ohms-1 | TOP=L2:L3=L2/L4:L6=L5/L7:BOTTOM=L7 |
| Z50_SSD_A1_SMB_DATA | 50OHM_15S | BUS | 1 | 4.75 | 5 | 10 | 5 | 14 | 12 | 15 | 12 | 12 | 12 | 12 |  | 50 Ohms-1 | TOP=L2:L3=L2/L4:L6=L5/L7:BOTTOM=L7 |
| Z50_SSD_A1_SMB_DATA_LL | 50OHM_15S | BUS | 1 | 4.75 | 5 | 10 | 5 | 14 | 12 | 15 | 12 | 12 | 12 | 12 |  | 50 Ohms-1 | TOP=L2:L3=L2/L4:L6=L5/L7:BOTTOM=L7 |
| Z50_SSD_A1_SMB_DATA_LR | 50OHM_15S | BUS | 1 | 4.75 | 5 | 10 | 5 | 14 | 12 | 15 | 12 | 12 | 12 | 12 |  | 50 Ohms-1 | TOP=L2:L3=L2/L4:L6=L5/L7:BOTTOM=L7 |
| Z50_SSD_A1_SMB_DATA_R | 50OHM_15S | BUS | 1 | 4.75 | 5 | 10 | 5 | 14 | 12 | 15 | 12 | 12 | 12 | 12 |  | 50 Ohms-1 | TOP=L2:L3=L2/L4:L6=L5/L7:BOTTOM=L7 |
| Z50_SSD_B1_SMB_CLK | 50OHM_15S | BUS | 1 | 4.75 | 5 | 10 | 5 | 14 | 12 | 15 | 12 | 12 | 12 | 12 |  | 50 Ohms-1 | TOP=L2:L3=L2/L4:L6=L5/L7:BOTTOM=L7 |
| Z50_SSD_B1_SMB_CLK_LL | 50OHM_15S | BUS | 1 | 4.75 | 5 | 10 | 5 | 14 | 12 | 15 | 12 | 12 | 12 | 12 |  | 50 Ohms-1 | TOP=L2:L3=L2/L4:L6=L5/L7:BOTTOM=L7 |
| Z50_SSD_B1_SMB_CLK_LR | 50OHM_15S | BUS | 1 | 4.75 | 5 | 10 | 5 | 14 | 12 | 15 | 12 | 12 | 12 | 12 |  | 50 Ohms-1 | TOP=L2:L3=L2/L4:L6=L5/L7:BOTTOM=L7 |
| Z50_SSD_B1_SMB_CLK_R | 50OHM_15S | BUS | 1 | 4.75 | 5 | 10 | 5 | 14 | 12 | 15 | 12 | 12 | 12 | 12 |  | 50 Ohms-1 | TOP=L2:L3=L2/L4:L6=L5/L7:BOTTOM=L7 |
| Z50_SSD_B1_SMB_DATA | 50OHM_15S | BUS | 1 | 4.75 | 5 | 10 | 5 | 14 | 12 | 15 | 12 | 12 | 12 | 12 |  | 50 Ohms-1 | TOP=L2:L3=L2/L4:L6=L5/L7:BOTTOM=L7 |
| Z50_SSD_B1_SMB_DATA_LL | 50OHM_15S | BUS | 1 | 4.75 | 5 | 10 | 5 | 14 | 12 | 15 | 12 | 12 | 12 | 12 |  | 50 Ohms-1 | TOP=L2:L3=L2/L4:L6=L5/L7:BOTTOM=L7 |
| Z50_SSD_B1_SMB_DATA_LR | 50OHM_15S | BUS | 1 | 4.75 | 5 | 10 | 5 | 14 | 12 | 15 | 12 | 12 | 12 | 12 |  | 50 Ohms-1 | TOP=L2:L3=L2/L4:L6=L5/L7:BOTTOM=L7 |
| Z50_SSD_B1_SMB_DATA_R | 50OHM_15S | BUS | 1 | 4.75 | 5 | 10 | 5 | 14 | 12 | 15 | 12 | 12 | 12 | 12 |  | 50 Ohms-1 | TOP=L2:L3=L2/L4:L6=L5/L7:BOTTOM=L7 |
| Z50_TEMP_1_CLK | 50OHM_15S | BUS | 1 | 4.75 | 5 | 10 | 5 | 14 | 12 | 15 | 12 | 12 | 12 | 12 |  | 50 Ohms-1 | TOP=L2:L3=L2/L4:L6=L5/L7:BOTTOM=L7 |
| Z50_TEMP_1_DATA | 50OHM_15S | BUS | 1 | 4.75 | 5 | 10 | 5 | 14 | 12 | 15 | 12 | 12 | 12 | 12 |  | 50 Ohms-1 | TOP=L2:L3=L2/L4:L6=L5/L7:BOTTOM=L7 |
| D85_PCIE_A_REFCLK_N | D85_PCIE_A_REFCLK-DIFF1 | PAIR | 1 | 5.38 | 5 | 10 | 5 | 12 | 15 | 36 | 12 | 12 | 12 | 12 | 6.2 | 85 Ohms | TOP=L2:L3=L2/L4:L6=L5/L7:BOTTOM=L7 |
| D85_PCIE_A_REFCLK_N | D85_PCIE_A_REFCLK-DIFF1 | PAIR | 2 | 6.88 | 5 | 10 | 5 | 12 | 15 | 20 | 12 | 5 | 12 | 12 | 5.62 | 85 Ohms | TOP=L2:L3=L2/L4:L6=L5/L7:BOTTOM=L7 |
| D85_PCIE_A_REFCLK_N | D85_PCIE_A_REFCLK-DIFF1 | PAIR | 3 | 5.25 | 5 | 10 | 5 | 12 | 15 | 20 | 12 | 5 | 12 | 12 | 7.5 | 85 Ohms | TOP=L2:L3=L2/L4:L6=L5/L7:BOTTOM=L7 |
| D85_PCIE_A_REFCLK_N | D85_PCIE_A_REFCLK-DIFF1 | PAIR | 4 | 6.88 | 5 | 10 | 5 | 12 | 15 | 20 | 12 | 5 | 12 | 12 | 5.62 | 85 Ohms | TOP=L2:L3=L2/L4:L6=L5/L7:BOTTOM=L7 |
| D85_PCIE_A_REFCLK_N | D85_PCIE_A_REFCLK-DIFF1 | PAIR | 5 | 6.88 | 5 | 10 | 5 | 12 | 15 | 20 | 12 | 5 | 12 | 12 | 5.62 | 85 Ohms | TOP=L2:L3=L2/L4:L6=L5/L7:BOTTOM=L7 |
| D85_PCIE_A_REFCLK_N | D85_PCIE_A_REFCLK-DIFF1 | PAIR | 6 | 5.25 | 5 | 10 | 5 | 12 | 15 | 20 | 12 | 5 | 12 | 12 | 7.5 | 85 Ohms | TOP=L2:L3=L2/L4:L6=L5/L7:BOTTOM=L7 |
| D85_PCIE_A_REFCLK_N | D85_PCIE_A_REFCLK-DIFF1 | PAIR | 7 | 6.88 | 5 | 10 | 5 | 12 | 15 | 20 | 12 | 5 | 12 | 12 | 5.62 | 85 Ohms | TOP=L2:L3=L2/L4:L6=L5/L7:BOTTOM=L7 |
| D85_PCIE_A_REFCLK_N | D85_PCIE_A_REFCLK-DIFF1 | PAIR | 8 | 5.38 | 5 | 10 | 5 | 12 | 15 | 36 | 12 | 12 | 12 | 12 | 6.2 | 85 Ohms | TOP=L2:L3=L2/L4:L6=L5/L7:BOTTOM=L7 |
| D85_PCIE_A_REFCLK_P | D85_PCIE_A_REFCLK-DIFF1 | PAIR | 1 | 5.38 | 5 | 10 | 5 | 12 | 15 | 36 | 12 | 12 | 12 | 12 | 6.2 | 85 Ohms | TOP=L2:L3=L2/L4:L6=L5/L7:BOTTOM=L7 |
| D85_PCIE_A_REFCLK_P | D85_PCIE_A_REFCLK-DIFF1 | PAIR | 2 | 6.88 | 5 | 10 | 5 | 12 | 15 | 20 | 12 | 5 | 12 | 12 | 5.62 | 85 Ohms | TOP=L2:L3=L2/L4:L6=L5/L7:BOTTOM=L7 |
| D85_PCIE_A_REFCLK_P | D85_PCIE_A_REFCLK-DIFF1 | PAIR | 3 | 5.25 | 5 | 10 | 5 | 12 | 15 | 20 | 12 | 5 | 12 | 12 | 7.5 | 85 Ohms | TOP=L2:L3=L2/L4:L6=L5/L7:BOTTOM=L7 |
| D85_PCIE_A_REFCLK_P | D85_PCIE_A_REFCLK-DIFF1 | PAIR | 4 | 6.88 | 5 | 10 | 5 | 12 | 15 | 20 | 12 | 5 | 12 | 12 | 5.62 | 85 Ohms | TOP=L2:L3=L2/L4:L6=L5/L7:BOTTOM=L7 |
| D85_PCIE_A_REFCLK_P | D85_PCIE_A_REFCLK-DIFF1 | PAIR | 5 | 6.88 | 5 | 10 | 5 | 12 | 15 | 20 | 12 | 5 | 12 | 12 | 5.62 | 85 Ohms | TOP=L2:L3=L2/L4:L6=L5/L7:BOTTOM=L7 |
| D85_PCIE_A_REFCLK_P | D85_PCIE_A_REFCLK-DIFF1 | PAIR | 6 | 5.25 | 5 | 10 | 5 | 12 | 15 | 20 | 12 | 5 | 12 | 12 | 7.5 | 85 Ohms | TOP=L2:L3=L2/L4:L6=L5/L7:BOTTOM=L7 |
| D85_PCIE_A_REFCLK_P | D85_PCIE_A_REFCLK-DIFF1 | PAIR | 7 | 6.88 | 5 | 10 | 5 | 12 | 15 | 20 | 12 | 5 | 12 | 12 | 5.62 | 85 Ohms | TOP=L2:L3=L2/L4:L6=L5/L7:BOTTOM=L7 |
| D85_PCIE_A_REFCLK_P | D85_PCIE_A_REFCLK-DIFF1 | PAIR | 8 | 5.38 | 5 | 10 | 5 | 12 | 15 | 36 | 12 | 12 | 12 | 12 | 6.2 | 85 Ohms | TOP=L2:L3=L2/L4:L6=L5/L7:BOTTOM=L7 |
| D85_PCIE_A_RX0_N | D85_PCIE_A_RX0-DIFF1 | PAIR | 1 | 5.38 | 5 | 10 | 5 | 12 | 15 | 36 | 12 | 12 | 12 | 12 | 6.2 | 85 Ohms | TOP=L2:L3=L2/L4:L6=L5/L7:BOTTOM=L7 |
| D85_PCIE_A_RX0_N | D85_PCIE_A_RX0-DIFF1 | PAIR | 2 | 6.88 | 5 | 10 | 5 | 12 | 15 | 20 | 12 | 5 | 12 | 12 | 5.62 | 85 Ohms | TOP=L2:L3=L2/L4:L6=L5/L7:BOTTOM=L7 |
| D85_PCIE_A_RX0_N | D85_PCIE_A_RX0-DIFF1 | PAIR | 3 | 5.25 | 5 | 10 | 5 | 12 | 15 | 20 | 12 | 5 | 12 | 12 | 7.5 | 85 Ohms | TOP=L2:L3=L2/L4:L6=L5/L7:BOTTOM=L7 |
| D85_PCIE_A_RX0_N | D85_PCIE_A_RX0-DIFF1 | PAIR | 4 | 6.88 | 5 | 10 | 5 | 12 | 15 | 20 | 12 | 5 | 12 | 12 | 5.62 | 85 Ohms | TOP=L2:L3=L2/L4:L6=L5/L7:BOTTOM=L7 |
| D85_PCIE_A_RX0_N | D85_PCIE_A_RX0-DIFF1 | PAIR | 5 | 6.88 | 5 | 10 | 5 | 12 | 15 | 20 | 12 | 5 | 12 | 12 | 5.62 | 85 Ohms | TOP=L2:L3=L2/L4:L6=L5/L7:BOTTOM=L7 |
| D85_PCIE_A_RX0_N | D85_PCIE_A_RX0-DIFF1 | PAIR | 6 | 5.25 | 5 | 10 | 5 | 12 | 15 | 20 | 12 | 5 | 12 | 12 | 7.5 | 85 Ohms | TOP=L2:L3=L2/L4:L6=L5/L7:BOTTOM=L7 |
| D85_PCIE_A_RX0_N | D85_PCIE_A_RX0-DIFF1 | PAIR | 7 | 6.88 | 5 | 10 | 5 | 12 | 15 | 20 | 12 | 5 | 12 | 12 | 5.62 | 85 Ohms | TOP=L2:L3=L2/L4:L6=L5/L7:BOTTOM=L7 |
| D85_PCIE_A_RX0_N | D85_PCIE_A_RX0-DIFF1 | PAIR | 8 | 5.38 | 5 | 10 | 5 | 12 | 15 | 36 | 12 | 12 | 12 | 12 | 6.2 | 85 Ohms | TOP=L2:L3=L2/L4:L6=L5/L7:BOTTOM=L7 |
| D85_PCIE_A_RX0_P | D85_PCIE_A_RX0-DIFF1 | PAIR | 1 | 5.38 | 5 | 10 | 5 | 12 | 15 | 36 | 12 | 12 | 12 | 12 | 6.2 | 85 Ohms | TOP=L2:L3=L2/L4:L6=L5/L7:BOTTOM=L7 |
| D85_PCIE_A_RX0_P | D85_PCIE_A_RX0-DIFF1 | PAIR | 2 | 6.88 | 5 | 10 | 5 | 12 | 15 | 20 | 12 | 5 | 12 | 12 | 5.62 | 85 Ohms | TOP=L2:L3=L2/L4:L6=L5/L7:BOTTOM=L7 |
| D85_PCIE_A_RX0_P | D85_PCIE_A_RX0-DIFF1 | PAIR | 3 | 5.25 | 5 | 10 | 5 | 12 | 15 | 20 | 12 | 5 | 12 | 12 | 7.5 | 85 Ohms | TOP=L2:L3=L2/L4:L6=L5/L7:BOTTOM=L7 |
| D85_PCIE_A_RX0_P | D85_PCIE_A_RX0-DIFF1 | PAIR | 4 | 6.88 | 5 | 10 | 5 | 12 | 15 | 20 | 12 | 5 | 12 | 12 | 5.62 | 85 Ohms | TOP=L2:L3=L2/L4:L6=L5/L7:BOTTOM=L7 |
| D85_PCIE_A_RX0_P | D85_PCIE_A_RX0-DIFF1 | PAIR | 5 | 6.88 | 5 | 10 | 5 | 12 | 15 | 20 | 12 | 5 | 12 | 12 | 5.62 | 85 Ohms | TOP=L2:L3=L2/L4:L6=L5/L7:BOTTOM=L7 |
| D85_PCIE_A_RX0_P | D85_PCIE_A_RX0-DIFF1 | PAIR | 6 | 5.25 | 5 | 10 | 5 | 12 | 15 | 20 | 12 | 5 | 12 | 12 | 7.5 | 85 Ohms | TOP=L2:L3=L2/L4:L6=L5/L7:BOTTOM=L7 |
| D85_PCIE_A_RX0_P | D85_PCIE_A_RX0-DIFF1 | PAIR | 7 | 6.88 | 5 | 10 | 5 | 12 | 15 | 20 | 12 | 5 | 12 | 12 | 5.62 | 85 Ohms | TOP=L2:L3=L2/L4:L6=L5/L7:BOTTOM=L7 |
| D85_PCIE_A_RX0_P | D85_PCIE_A_RX0-DIFF1 | PAIR | 8 | 5.38 | 5 | 10 | 5 | 12 | 15 | 36 | 12 | 12 | 12 | 12 | 6.2 | 85 Ohms | TOP=L2:L3=L2/L4:L6=L5/L7:BOTTOM=L7 |
| D85_PCIE_A_RX1_N | D85_PCIE_A_RX1-DIFF1 | PAIR | 1 | 5.38 | 5 | 10 | 5 | 14 | 15 | 36 | 12 | 12 | 12 | 12 | 6.2 | 85 Ohms | TOP=L2:L3=L2/L4:L6=L5/L7:BOTTOM=L7 |
| D85_PCIE_A_RX1_N | D85_PCIE_A_RX1-DIFF1 | PAIR | 2 | 6.88 | 5 | 10 | 5 | 14 | 15 | 20 | 12 | 5 | 12 | 12 | 5.62 | 85 Ohms | TOP=L2:L3=L2/L4:L6=L5/L7:BOTTOM=L7 |
| D85_PCIE_A_RX1_N | D85_PCIE_A_RX1-DIFF1 | PAIR | 3 | 5.25 | 5 | 10 | 5 | 14 | 15 | 20 | 12 | 5 | 12 | 12 | 7.5 | 85 Ohms | TOP=L2:L3=L2/L4:L6=L5/L7:BOTTOM=L7 |
| D85_PCIE_A_RX1_N | D85_PCIE_A_RX1-DIFF1 | PAIR | 4 | 6.88 | 5 | 10 | 5 | 14 | 15 | 20 | 12 | 5 | 12 | 12 | 5.62 | 85 Ohms | TOP=L2:L3=L2/L4:L6=L5/L7:BOTTOM=L7 |
| D85_PCIE_A_RX1_N | D85_PCIE_A_RX1-DIFF1 | PAIR | 5 | 6.88 | 5 | 10 | 5 | 14 | 15 | 20 | 12 | 5 | 12 | 12 | 5.62 | 85 Ohms | TOP=L2:L3=L2/L4:L6=L5/L7:BOTTOM=L7 |
| D85_PCIE_A_RX1_N | D85_PCIE_A_RX1-DIFF1 | PAIR | 6 | 5.25 | 5 | 10 | 5 | 14 | 15 | 20 | 12 | 5 | 12 | 12 | 7.5 | 85 Ohms | TOP=L2:L3=L2/L4:L6=L5/L7:BOTTOM=L7 |
| D85_PCIE_A_RX1_N | D85_PCIE_A_RX1-DIFF1 | PAIR | 7 | 6.88 | 5 | 10 | 5 | 14 | 15 | 20 | 12 | 5 | 12 | 12 | 5.62 | 85 Ohms | TOP=L2:L3=L2/L4:L6=L5/L7:BOTTOM=L7 |
| D85_PCIE_A_RX1_N | D85_PCIE_A_RX1-DIFF1 | PAIR | 8 | 5.38 | 5 | 10 | 5 | 14 | 15 | 36 | 12 | 12 | 12 | 12 | 6.2 | 85 Ohms | TOP=L2:L3=L2/L4:L6=L5/L7:BOTTOM=L7 |
| D85_PCIE_A_RX1_P | D85_PCIE_A_RX1-DIFF1 | PAIR | 1 | 5.38 | 5 | 10 | 5 | 14 | 15 | 36 | 12 | 12 | 12 | 12 | 6.2 | 85 Ohms | TOP=L2:L3=L2/L4:L6=L5/L7:BOTTOM=L7 |
| D85_PCIE_A_RX1_P | D85_PCIE_A_RX1-DIFF1 | PAIR | 2 | 6.88 | 5 | 10 | 5 | 14 | 15 | 20 | 12 | 5 | 12 | 12 | 5.62 | 85 Ohms | TOP=L2:L3=L2/L4:L6=L5/L7:BOTTOM=L7 |
| D85_PCIE_A_RX1_P | D85_PCIE_A_RX1-DIFF1 | PAIR | 3 | 5.25 | 5 | 10 | 5 | 14 | 15 | 20 | 12 | 5 | 12 | 12 | 7.5 | 85 Ohms | TOP=L2:L3=L2/L4:L6=L5/L7:BOTTOM=L7 |
| D85_PCIE_A_RX1_P | D85_PCIE_A_RX1-DIFF1 | PAIR | 4 | 6.88 | 5 | 10 | 5 | 14 | 15 | 20 | 12 | 5 | 12 | 12 | 5.62 | 85 Ohms | TOP=L2:L3=L2/L4:L6=L5/L7:BOTTOM=L7 |
| D85_PCIE_A_RX1_P | D85_PCIE_A_RX1-DIFF1 | PAIR | 5 | 6.88 | 5 | 10 | 5 | 14 | 15 | 20 | 12 | 5 | 12 | 12 | 5.62 | 85 Ohms | TOP=L2:L3=L2/L4:L6=L5/L7:BOTTOM=L7 |
| D85_PCIE_A_RX1_P | D85_PCIE_A_RX1-DIFF1 | PAIR | 6 | 5.25 | 5 | 10 | 5 | 14 | 15 | 20 | 12 | 5 | 12 | 12 | 7.5 | 85 Ohms | TOP=L2:L3=L2/L4:L6=L5/L7:BOTTOM=L7 |
| D85_PCIE_A_RX1_P | D85_PCIE_A_RX1-DIFF1 | PAIR | 7 | 6.88 | 5 | 10 | 5 | 14 | 15 | 20 | 12 | 5 | 12 | 12 | 5.62 | 85 Ohms | TOP=L2:L3=L2/L4:L6=L5/L7:BOTTOM=L7 |
| D85_PCIE_A_RX1_P | D85_PCIE_A_RX1-DIFF1 | PAIR | 8 | 5.38 | 5 | 10 | 5 | 14 | 15 | 36 | 12 | 12 | 12 | 12 | 6.2 | 85 Ohms | TOP=L2:L3=L2/L4:L6=L5/L7:BOTTOM=L7 |
| D85_PCIE_A_TX0_N | D85_PCIE_A_TX0-DIFF1 | PAIR | 1 | 5.38 | 5 | 10 | 5 | 12 | 15 | 36 | 12 | 12 | 12 | 12 | 6.2 | 85 Ohms | TOP=L2:L3=L2/L4:L6=L5/L7:BOTTOM=L7 |
| D85_PCIE_A_TX0_N | D85_PCIE_A_TX0-DIFF1 | PAIR | 2 | 6.88 | 5 | 10 | 5 | 12 | 15 | 20 | 12 | 5 | 12 | 12 | 5.62 | 85 Ohms | TOP=L2:L3=L2/L4:L6=L5/L7:BOTTOM=L7 |
| D85_PCIE_A_TX0_N | D85_PCIE_A_TX0-DIFF1 | PAIR | 3 | 5.25 | 5 | 10 | 5 | 12 | 15 | 20 | 12 | 5 | 12 | 12 | 7.5 | 85 Ohms | TOP=L2:L3=L2/L4:L6=L5/L7:BOTTOM=L7 |
| D85_PCIE_A_TX0_N | D85_PCIE_A_TX0-DIFF1 | PAIR | 4 | 6.88 | 5 | 10 | 5 | 12 | 15 | 20 | 12 | 5 | 12 | 12 | 5.62 | 85 Ohms | TOP=L2:L3=L2/L4:L6=L5/L7:BOTTOM=L7 |
| D85_PCIE_A_TX0_N | D85_PCIE_A_TX0-DIFF1 | PAIR | 5 | 6.88 | 5 | 10 | 5 | 12 | 15 | 20 | 12 | 5 | 12 | 12 | 5.62 | 85 Ohms | TOP=L2:L3=L2/L4:L6=L5/L7:BOTTOM=L7 |
| D85_PCIE_A_TX0_N | D85_PCIE_A_TX0-DIFF1 | PAIR | 6 | 5.25 | 5 | 10 | 5 | 12 | 15 | 20 | 12 | 5 | 12 | 12 | 7.5 | 85 Ohms | TOP=L2:L3=L2/L4:L6=L5/L7:BOTTOM=L7 |
| D85_PCIE_A_TX0_N | D85_PCIE_A_TX0-DIFF1 | PAIR | 7 | 6.88 | 5 | 10 | 5 | 12 | 15 | 20 | 12 | 5 | 12 | 12 | 5.62 | 85 Ohms | TOP=L2:L3=L2/L4:L6=L5/L7:BOTTOM=L7 |
| D85_PCIE_A_TX0_N | D85_PCIE_A_TX0-DIFF1 | PAIR | 8 | 5.38 | 5 | 10 | 5 | 12 | 15 | 36 | 12 | 12 | 12 | 12 | 6.2 | 85 Ohms | TOP=L2:L3=L2/L4:L6=L5/L7:BOTTOM=L7 |
| D85_PCIE_A_TX0_P | D85_PCIE_A_TX0-DIFF1 | PAIR | 1 | 5.38 | 5 | 10 | 5 | 12 | 15 | 36 | 12 | 12 | 12 | 12 | 6.2 | 85 Ohms | TOP=L2:L3=L2/L4:L6=L5/L7:BOTTOM=L7 |
| D85_PCIE_A_TX0_P | D85_PCIE_A_TX0-DIFF1 | PAIR | 2 | 6.88 | 5 | 10 | 5 | 12 | 15 | 20 | 12 | 5 | 12 | 12 | 5.62 | 85 Ohms | TOP=L2:L3=L2/L4:L6=L5/L7:BOTTOM=L7 |
| D85_PCIE_A_TX0_P | D85_PCIE_A_TX0-DIFF1 | PAIR | 3 | 5.25 | 5 | 10 | 5 | 12 | 15 | 20 | 12 | 5 | 12 | 12 | 7.5 | 85 Ohms | TOP=L2:L3=L2/L4:L6=L5/L7:BOTTOM=L7 |
| D85_PCIE_A_TX0_P | D85_PCIE_A_TX0-DIFF1 | PAIR | 4 | 6.88 | 5 | 10 | 5 | 12 | 15 | 20 | 12 | 5 | 12 | 12 | 5.62 | 85 Ohms | TOP=L2:L3=L2/L4:L6=L5/L7:BOTTOM=L7 |
| D85_PCIE_A_TX0_P | D85_PCIE_A_TX0-DIFF1 | PAIR | 5 | 6.88 | 5 | 10 | 5 | 12 | 15 | 20 | 12 | 5 | 12 | 12 | 5.62 | 85 Ohms | TOP=L2:L3=L2/L4:L6=L5/L7:BOTTOM=L7 |
| D85_PCIE_A_TX0_P | D85_PCIE_A_TX0-DIFF1 | PAIR | 6 | 5.25 | 5 | 10 | 5 | 12 | 15 | 20 | 12 | 5 | 12 | 12 | 7.5 | 85 Ohms | TOP=L2:L3=L2/L4:L6=L5/L7:BOTTOM=L7 |
| D85_PCIE_A_TX0_P | D85_PCIE_A_TX0-DIFF1 | PAIR | 7 | 6.88 | 5 | 10 | 5 | 12 | 15 | 20 | 12 | 5 | 12 | 12 | 5.62 | 85 Ohms | TOP=L2:L3=L2/L4:L6=L5/L7:BOTTOM=L7 |
| D85_PCIE_A_TX0_P | D85_PCIE_A_TX0-DIFF1 | PAIR | 8 | 5.38 | 5 | 10 | 5 | 12 | 15 | 36 | 12 | 12 | 12 | 12 | 6.2 | 85 Ohms | TOP=L2:L3=L2/L4:L6=L5/L7:BOTTOM=L7 |
| D85_PCIE_A_TX1_N | D85_PCIE_A_TX1-DIFF1 | PAIR | 1 | 5.38 | 5 | 10 | 5 | 14 | 15 | 36 | 12 | 12 | 12 | 12 | 6.2 | 85 Ohms | TOP=L2:L3=L2/L4:L6=L5/L7:BOTTOM=L7 |
| D85_PCIE_A_TX1_N | D85_PCIE_A_TX1-DIFF1 | PAIR | 2 | 6.88 | 5 | 10 | 5 | 14 | 15 | 20 | 12 | 5 | 12 | 12 | 5.62 | 85 Ohms | TOP=L2:L3=L2/L4:L6=L5/L7:BOTTOM=L7 |
| D85_PCIE_A_TX1_N | D85_PCIE_A_TX1-DIFF1 | PAIR | 3 | 5.25 | 5 | 10 | 5 | 14 | 15 | 20 | 12 | 5 | 12 | 12 | 7.5 | 85 Ohms | TOP=L2:L3=L2/L4:L6=L5/L7:BOTTOM=L7 |
| D85_PCIE_A_TX1_N | D85_PCIE_A_TX1-DIFF1 | PAIR | 4 | 6.88 | 5 | 10 | 5 | 14 | 15 | 20 | 12 | 5 | 12 | 12 | 5.62 | 85 Ohms | TOP=L2:L3=L2/L4:L6=L5/L7:BOTTOM=L7 |
| D85_PCIE_A_TX1_N | D85_PCIE_A_TX1-DIFF1 | PAIR | 5 | 6.88 | 5 | 10 | 5 | 14 | 15 | 20 | 12 | 5 | 12 | 12 | 5.62 | 85 Ohms | TOP=L2:L3=L2/L4:L6=L5/L7:BOTTOM=L7 |
| D85_PCIE_A_TX1_N | D85_PCIE_A_TX1-DIFF1 | PAIR | 6 | 5.25 | 5 | 10 | 5 | 14 | 15 | 20 | 12 | 5 | 12 | 12 | 7.5 | 85 Ohms | TOP=L2:L3=L2/L4:L6=L5/L7:BOTTOM=L7 |
| D85_PCIE_A_TX1_N | D85_PCIE_A_TX1-DIFF1 | PAIR | 7 | 6.88 | 5 | 10 | 5 | 14 | 15 | 20 | 12 | 5 | 12 | 12 | 5.62 | 85 Ohms | TOP=L2:L3=L2/L4:L6=L5/L7:BOTTOM=L7 |
| D85_PCIE_A_TX1_N | D85_PCIE_A_TX1-DIFF1 | PAIR | 8 | 5.38 | 5 | 10 | 5 | 14 | 15 | 36 | 12 | 12 | 12 | 12 | 6.2 | 85 Ohms | TOP=L2:L3=L2/L4:L6=L5/L7:BOTTOM=L7 |
| D85_PCIE_A_TX1_P | D85_PCIE_A_TX1-DIFF1 | PAIR | 1 | 5.38 | 5 | 10 | 5 | 14 | 15 | 36 | 12 | 12 | 12 | 12 | 6.2 | 85 Ohms | TOP=L2:L3=L2/L4:L6=L5/L7:BOTTOM=L7 |
| D85_PCIE_A_TX1_P | D85_PCIE_A_TX1-DIFF1 | PAIR | 2 | 6.88 | 5 | 10 | 5 | 14 | 15 | 20 | 12 | 5 | 12 | 12 | 5.62 | 85 Ohms | TOP=L2:L3=L2/L4:L6=L5/L7:BOTTOM=L7 |
| D85_PCIE_A_TX1_P | D85_PCIE_A_TX1-DIFF1 | PAIR | 3 | 5.25 | 5 | 10 | 5 | 14 | 15 | 20 | 12 | 5 | 12 | 12 | 7.5 | 85 Ohms | TOP=L2:L3=L2/L4:L6=L5/L7:BOTTOM=L7 |
| D85_PCIE_A_TX1_P | D85_PCIE_A_TX1-DIFF1 | PAIR | 4 | 6.88 | 5 | 10 | 5 | 14 | 15 | 20 | 12 | 5 | 12 | 12 | 5.62 | 85 Ohms | TOP=L2:L3=L2/L4:L6=L5/L7:BOTTOM=L7 |
| D85_PCIE_A_TX1_P | D85_PCIE_A_TX1-DIFF1 | PAIR | 5 | 6.88 | 5 | 10 | 5 | 14 | 15 | 20 | 12 | 5 | 12 | 12 | 5.62 | 85 Ohms | TOP=L2:L3=L2/L4:L6=L5/L7:BOTTOM=L7 |
| D85_PCIE_A_TX1_P | D85_PCIE_A_TX1-DIFF1 | PAIR | 6 | 5.25 | 5 | 10 | 5 | 14 | 15 | 20 | 12 | 5 | 12 | 12 | 7.5 | 85 Ohms | TOP=L2:L3=L2/L4:L6=L5/L7:BOTTOM=L7 |
| D85_PCIE_A_TX1_P | D85_PCIE_A_TX1-DIFF1 | PAIR | 7 | 6.88 | 5 | 10 | 5 | 14 | 15 | 20 | 12 | 5 | 12 | 12 | 5.62 | 85 Ohms | TOP=L2:L3=L2/L4:L6=L5/L7:BOTTOM=L7 |
| D85_PCIE_A_TX1_P | D85_PCIE_A_TX1-DIFF1 | PAIR | 8 | 5.38 | 5 | 10 | 5 | 14 | 15 | 36 | 12 | 12 | 12 | 12 | 6.2 | 85 Ohms | TOP=L2:L3=L2/L4:L6=L5/L7:BOTTOM=L7 |
| D85_PCIE_B_REFCLK_N | D85_PCIE_B_REFCLK-DIFF1 | PAIR | 1 | 5.38 | 5 | 10 | 5 | 12 | 15 | 36 | 12 | 12 | 12 | 12 | 6.2 | 85 Ohms | TOP=L2:L3=L2/L4:L6=L5/L7:BOTTOM=L7 |
| D85_PCIE_B_REFCLK_N | D85_PCIE_B_REFCLK-DIFF1 | PAIR | 2 | 6.88 | 5 | 10 | 5 | 12 | 15 | 20 | 12 | 5 | 12 | 12 | 5.62 | 85 Ohms | TOP=L2:L3=L2/L4:L6=L5/L7:BOTTOM=L7 |
| D85_PCIE_B_REFCLK_N | D85_PCIE_B_REFCLK-DIFF1 | PAIR | 3 | 5.25 | 5 | 10 | 5 | 12 | 15 | 20 | 12 | 5 | 12 | 12 | 7.5 | 85 Ohms | TOP=L2:L3=L2/L4:L6=L5/L7:BOTTOM=L7 |
| D85_PCIE_B_REFCLK_N | D85_PCIE_B_REFCLK-DIFF1 | PAIR | 4 | 6.88 | 5 | 10 | 5 | 12 | 15 | 20 | 12 | 5 | 12 | 12 | 5.62 | 85 Ohms | TOP=L2:L3=L2/L4:L6=L5/L7:BOTTOM=L7 |
| D85_PCIE_B_REFCLK_N | D85_PCIE_B_REFCLK-DIFF1 | PAIR | 5 | 6.88 | 5 | 10 | 5 | 12 | 15 | 20 | 12 | 5 | 12 | 12 | 5.62 | 85 Ohms | TOP=L2:L3=L2/L4:L6=L5/L7:BOTTOM=L7 |
| D85_PCIE_B_REFCLK_N | D85_PCIE_B_REFCLK-DIFF1 | PAIR | 6 | 5.25 | 5 | 10 | 5 | 12 | 15 | 20 | 12 | 5 | 12 | 12 | 7.5 | 85 Ohms | TOP=L2:L3=L2/L4:L6=L5/L7:BOTTOM=L7 |
| D85_PCIE_B_REFCLK_N | D85_PCIE_B_REFCLK-DIFF1 | PAIR | 7 | 6.88 | 5 | 10 | 5 | 12 | 15 | 20 | 12 | 5 | 12 | 12 | 5.62 | 85 Ohms | TOP=L2:L3=L2/L4:L6=L5/L7:BOTTOM=L7 |
| D85_PCIE_B_REFCLK_N | D85_PCIE_B_REFCLK-DIFF1 | PAIR | 8 | 5.38 | 5 | 10 | 5 | 12 | 15 | 36 | 12 | 12 | 12 | 12 | 6.2 | 85 Ohms | TOP=L2:L3=L2/L4:L6=L5/L7:BOTTOM=L7 |
| D85_PCIE_B_REFCLK_P | D85_PCIE_B_REFCLK-DIFF1 | PAIR | 1 | 5.38 | 5 | 10 | 5 | 12 | 15 | 36 | 12 | 12 | 12 | 12 | 6.2 | 85 Ohms | TOP=L2:L3=L2/L4:L6=L5/L7:BOTTOM=L7 |
| D85_PCIE_B_REFCLK_P | D85_PCIE_B_REFCLK-DIFF1 | PAIR | 2 | 6.88 | 5 | 10 | 5 | 12 | 15 | 20 | 12 | 5 | 12 | 12 | 5.62 | 85 Ohms | TOP=L2:L3=L2/L4:L6=L5/L7:BOTTOM=L7 |
| D85_PCIE_B_REFCLK_P | D85_PCIE_B_REFCLK-DIFF1 | PAIR | 3 | 5.25 | 5 | 10 | 5 | 12 | 15 | 20 | 12 | 5 | 12 | 12 | 7.5 | 85 Ohms | TOP=L2:L3=L2/L4:L6=L5/L7:BOTTOM=L7 |
| D85_PCIE_B_REFCLK_P | D85_PCIE_B_REFCLK-DIFF1 | PAIR | 4 | 6.88 | 5 | 10 | 5 | 12 | 15 | 20 | 12 | 5 | 12 | 12 | 5.62 | 85 Ohms | TOP=L2:L3=L2/L4:L6=L5/L7:BOTTOM=L7 |
| D85_PCIE_B_REFCLK_P | D85_PCIE_B_REFCLK-DIFF1 | PAIR | 5 | 6.88 | 5 | 10 | 5 | 12 | 15 | 20 | 12 | 5 | 12 | 12 | 5.62 | 85 Ohms | TOP=L2:L3=L2/L4:L6=L5/L7:BOTTOM=L7 |
| D85_PCIE_B_REFCLK_P | D85_PCIE_B_REFCLK-DIFF1 | PAIR | 6 | 5.25 | 5 | 10 | 5 | 12 | 15 | 20 | 12 | 5 | 12 | 12 | 7.5 | 85 Ohms | TOP=L2:L3=L2/L4:L6=L5/L7:BOTTOM=L7 |
| D85_PCIE_B_REFCLK_P | D85_PCIE_B_REFCLK-DIFF1 | PAIR | 7 | 6.88 | 5 | 10 | 5 | 12 | 15 | 20 | 12 | 5 | 12 | 12 | 5.62 | 85 Ohms | TOP=L2:L3=L2/L4:L6=L5/L7:BOTTOM=L7 |
| D85_PCIE_B_REFCLK_P | D85_PCIE_B_REFCLK-DIFF1 | PAIR | 8 | 5.38 | 5 | 10 | 5 | 12 | 15 | 36 | 12 | 12 | 12 | 12 | 6.2 | 85 Ohms | TOP=L2:L3=L2/L4:L6=L5/L7:BOTTOM=L7 |
| D85_PCIE_B_RX0_N | D85_PCIE_B_RX0-DIFF1 | PAIR | 1 | 5.38 | 5 | 10 | 5 | 12 | 15 | 36 | 12 | 12 | 12 | 12 | 6.2 | 85 Ohms | TOP=L2:L3=L2/L4:L6=L5/L7:BOTTOM=L7 |
| D85_PCIE_B_RX0_N | D85_PCIE_B_RX0-DIFF1 | PAIR | 2 | 6.88 | 5 | 10 | 5 | 12 | 15 | 20 | 12 | 5 | 12 | 12 | 5.62 | 85 Ohms | TOP=L2:L3=L2/L4:L6=L5/L7:BOTTOM=L7 |
| D85_PCIE_B_RX0_N | D85_PCIE_B_RX0-DIFF1 | PAIR | 3 | 5.25 | 5 | 10 | 5 | 12 | 15 | 20 | 12 | 5 | 12 | 12 | 7.5 | 85 Ohms | TOP=L2:L3=L2/L4:L6=L5/L7:BOTTOM=L7 |
| D85_PCIE_B_RX0_N | D85_PCIE_B_RX0-DIFF1 | PAIR | 4 | 6.88 | 5 | 10 | 5 | 12 | 15 | 20 | 12 | 5 | 12 | 12 | 5.62 | 85 Ohms | TOP=L2:L3=L2/L4:L6=L5/L7:BOTTOM=L7 |
| D85_PCIE_B_RX0_N | D85_PCIE_B_RX0-DIFF1 | PAIR | 5 | 6.88 | 5 | 10 | 5 | 12 | 15 | 20 | 12 | 5 | 12 | 12 | 5.62 | 85 Ohms | TOP=L2:L3=L2/L4:L6=L5/L7:BOTTOM=L7 |
| D85_PCIE_B_RX0_N | D85_PCIE_B_RX0-DIFF1 | PAIR | 6 | 5.25 | 5 | 10 | 5 | 12 | 15 | 20 | 12 | 5 | 12 | 12 | 7.5 | 85 Ohms | TOP=L2:L3=L2/L4:L6=L5/L7:BOTTOM=L7 |
| D85_PCIE_B_RX0_N | D85_PCIE_B_RX0-DIFF1 | PAIR | 7 | 6.88 | 5 | 10 | 5 | 12 | 15 | 20 | 12 | 5 | 12 | 12 | 5.62 | 85 Ohms | TOP=L2:L3=L2/L4:L6=L5/L7:BOTTOM=L7 |
| D85_PCIE_B_RX0_N | D85_PCIE_B_RX0-DIFF1 | PAIR | 8 | 5.38 | 5 | 10 | 5 | 12 | 15 | 36 | 12 | 12 | 12 | 12 | 6.2 | 85 Ohms | TOP=L2:L3=L2/L4:L6=L5/L7:BOTTOM=L7 |
| D85_PCIE_B_RX0_P | D85_PCIE_B_RX0-DIFF1 | PAIR | 1 | 5.38 | 5 | 10 | 5 | 12 | 15 | 36 | 12 | 12 | 12 | 12 | 6.2 | 85 Ohms | TOP=L2:L3=L2/L4:L6=L5/L7:BOTTOM=L7 |
| D85_PCIE_B_RX0_P | D85_PCIE_B_RX0-DIFF1 | PAIR | 2 | 6.88 | 5 | 10 | 5 | 12 | 15 | 20 | 12 | 5 | 12 | 12 | 5.62 | 85 Ohms | TOP=L2:L3=L2/L4:L6=L5/L7:BOTTOM=L7 |
| D85_PCIE_B_RX0_P | D85_PCIE_B_RX0-DIFF1 | PAIR | 3 | 5.25 | 5 | 10 | 5 | 12 | 15 | 20 | 12 | 5 | 12 | 12 | 7.5 | 85 Ohms | TOP=L2:L3=L2/L4:L6=L5/L7:BOTTOM=L7 |
| D85_PCIE_B_RX0_P | D85_PCIE_B_RX0-DIFF1 | PAIR | 4 | 6.88 | 5 | 10 | 5 | 12 | 15 | 20 | 12 | 5 | 12 | 12 | 5.62 | 85 Ohms | TOP=L2:L3=L2/L4:L6=L5/L7:BOTTOM=L7 |
| D85_PCIE_B_RX0_P | D85_PCIE_B_RX0-DIFF1 | PAIR | 5 | 6.88 | 5 | 10 | 5 | 12 | 15 | 20 | 12 | 5 | 12 | 12 | 5.62 | 85 Ohms | TOP=L2:L3=L2/L4:L6=L5/L7:BOTTOM=L7 |
| D85_PCIE_B_RX0_P | D85_PCIE_B_RX0-DIFF1 | PAIR | 6 | 5.25 | 5 | 10 | 5 | 12 | 15 | 20 | 12 | 5 | 12 | 12 | 7.5 | 85 Ohms | TOP=L2:L3=L2/L4:L6=L5/L7:BOTTOM=L7 |
| D85_PCIE_B_RX0_P | D85_PCIE_B_RX0-DIFF1 | PAIR | 7 | 6.88 | 5 | 10 | 5 | 12 | 15 | 20 | 12 | 5 | 12 | 12 | 5.62 | 85 Ohms | TOP=L2:L3=L2/L4:L6=L5/L7:BOTTOM=L7 |
| D85_PCIE_B_RX0_P | D85_PCIE_B_RX0-DIFF1 | PAIR | 8 | 5.38 | 5 | 10 | 5 | 12 | 15 | 36 | 12 | 12 | 12 | 12 | 6.2 | 85 Ohms | TOP=L2:L3=L2/L4:L6=L5/L7:BOTTOM=L7 |
| D85_PCIE_B_RX1_N | D85_PCIE_B_RX1-DIFF1 | PAIR | 1 | 5.38 | 5 | 10 | 5 | 14 | 15 | 36 | 12 | 12 | 12 | 12 | 6.2 | 85 Ohms | TOP=L2:L3=L2/L4:L6=L5/L7:BOTTOM=L7 |
| D85_PCIE_B_RX1_N | D85_PCIE_B_RX1-DIFF1 | PAIR | 2 | 6.88 | 5 | 10 | 5 | 14 | 15 | 20 | 12 | 5 | 12 | 12 | 5.62 | 85 Ohms | TOP=L2:L3=L2/L4:L6=L5/L7:BOTTOM=L7 |
| D85_PCIE_B_RX1_N | D85_PCIE_B_RX1-DIFF1 | PAIR | 3 | 5.25 | 5 | 10 | 5 | 14 | 15 | 20 | 12 | 5 | 12 | 12 | 7.5 | 85 Ohms | TOP=L2:L3=L2/L4:L6=L5/L7:BOTTOM=L7 |
| D85_PCIE_B_RX1_N | D85_PCIE_B_RX1-DIFF1 | PAIR | 4 | 6.88 | 5 | 10 | 5 | 14 | 15 | 20 | 12 | 5 | 12 | 12 | 5.62 | 85 Ohms | TOP=L2:L3=L2/L4:L6=L5/L7:BOTTOM=L7 |
| D85_PCIE_B_RX1_N | D85_PCIE_B_RX1-DIFF1 | PAIR | 5 | 6.88 | 5 | 10 | 5 | 14 | 15 | 20 | 12 | 5 | 12 | 12 | 5.62 | 85 Ohms | TOP=L2:L3=L2/L4:L6=L5/L7:BOTTOM=L7 |
| D85_PCIE_B_RX1_N | D85_PCIE_B_RX1-DIFF1 | PAIR | 6 | 5.25 | 5 | 10 | 5 | 14 | 15 | 20 | 12 | 5 | 12 | 12 | 7.5 | 85 Ohms | TOP=L2:L3=L2/L4:L6=L5/L7:BOTTOM=L7 |
| D85_PCIE_B_RX1_N | D85_PCIE_B_RX1-DIFF1 | PAIR | 7 | 6.88 | 5 | 10 | 5 | 14 | 15 | 20 | 12 | 5 | 12 | 12 | 5.62 | 85 Ohms | TOP=L2:L3=L2/L4:L6=L5/L7:BOTTOM=L7 |
| D85_PCIE_B_RX1_N | D85_PCIE_B_RX1-DIFF1 | PAIR | 8 | 5.38 | 5 | 10 | 5 | 14 | 15 | 36 | 12 | 12 | 12 | 12 | 6.2 | 85 Ohms | TOP=L2:L3=L2/L4:L6=L5/L7:BOTTOM=L7 |
| D85_PCIE_B_RX1_P | D85_PCIE_B_RX1-DIFF1 | PAIR | 1 | 5.38 | 5 | 10 | 5 | 14 | 15 | 36 | 12 | 12 | 12 | 12 | 6.2 | 85 Ohms | TOP=L2:L3=L2/L4:L6=L5/L7:BOTTOM=L7 |
| D85_PCIE_B_RX1_P | D85_PCIE_B_RX1-DIFF1 | PAIR | 2 | 6.88 | 5 | 10 | 5 | 14 | 15 | 20 | 12 | 5 | 12 | 12 | 5.62 | 85 Ohms | TOP=L2:L3=L2/L4:L6=L5/L7:BOTTOM=L7 |
| D85_PCIE_B_RX1_P | D85_PCIE_B_RX1-DIFF1 | PAIR | 3 | 5.25 | 5 | 10 | 5 | 14 | 15 | 20 | 12 | 5 | 12 | 12 | 7.5 | 85 Ohms | TOP=L2:L3=L2/L4:L6=L5/L7:BOTTOM=L7 |
| D85_PCIE_B_RX1_P | D85_PCIE_B_RX1-DIFF1 | PAIR | 4 | 6.88 | 5 | 10 | 5 | 14 | 15 | 20 | 12 | 5 | 12 | 12 | 5.62 | 85 Ohms | TOP=L2:L3=L2/L4:L6=L5/L7:BOTTOM=L7 |
| D85_PCIE_B_RX1_P | D85_PCIE_B_RX1-DIFF1 | PAIR | 5 | 6.88 | 5 | 10 | 5 | 14 | 15 | 20 | 12 | 5 | 12 | 12 | 5.62 | 85 Ohms | TOP=L2:L3=L2/L4:L6=L5/L7:BOTTOM=L7 |
| D85_PCIE_B_RX1_P | D85_PCIE_B_RX1-DIFF1 | PAIR | 6 | 5.25 | 5 | 10 | 5 | 14 | 15 | 20 | 12 | 5 | 12 | 12 | 7.5 | 85 Ohms | TOP=L2:L3=L2/L4:L6=L5/L7:BOTTOM=L7 |
| D85_PCIE_B_RX1_P | D85_PCIE_B_RX1-DIFF1 | PAIR | 7 | 6.88 | 5 | 10 | 5 | 14 | 15 | 20 | 12 | 5 | 12 | 12 | 5.62 | 85 Ohms | TOP=L2:L3=L2/L4:L6=L5/L7:BOTTOM=L7 |
| D85_PCIE_B_RX1_P | D85_PCIE_B_RX1-DIFF1 | PAIR | 8 | 5.38 | 5 | 10 | 5 | 14 | 15 | 36 | 12 | 12 | 12 | 12 | 6.2 | 85 Ohms | TOP=L2:L3=L2/L4:L6=L5/L7:BOTTOM=L7 |
| D85_PCIE_B_TX0_N | D85_PCIE_B_TX0-DIFF1 | PAIR | 1 | 5.38 | 5 | 10 | 5 | 12 | 15 | 36 | 12 | 12 | 12 | 12 | 6.2 | 85 Ohms | TOP=L2:L3=L2/L4:L6=L5/L7:BOTTOM=L7 |
| D85_PCIE_B_TX0_N | D85_PCIE_B_TX0-DIFF1 | PAIR | 2 | 6.88 | 5 | 10 | 5 | 12 | 15 | 20 | 12 | 5 | 12 | 12 | 5.62 | 85 Ohms | TOP=L2:L3=L2/L4:L6=L5/L7:BOTTOM=L7 |
| D85_PCIE_B_TX0_N | D85_PCIE_B_TX0-DIFF1 | PAIR | 3 | 5.25 | 5 | 10 | 5 | 12 | 15 | 20 | 12 | 5 | 12 | 12 | 7.5 | 85 Ohms | TOP=L2:L3=L2/L4:L6=L5/L7:BOTTOM=L7 |
| D85_PCIE_B_TX0_N | D85_PCIE_B_TX0-DIFF1 | PAIR | 4 | 6.88 | 5 | 10 | 5 | 12 | 15 | 20 | 12 | 5 | 12 | 12 | 5.62 | 85 Ohms | TOP=L2:L3=L2/L4:L6=L5/L7:BOTTOM=L7 |
| D85_PCIE_B_TX0_N | D85_PCIE_B_TX0-DIFF1 | PAIR | 5 | 6.88 | 5 | 10 | 5 | 12 | 15 | 20 | 12 | 5 | 12 | 12 | 5.62 | 85 Ohms | TOP=L2:L3=L2/L4:L6=L5/L7:BOTTOM=L7 |
| D85_PCIE_B_TX0_N | D85_PCIE_B_TX0-DIFF1 | PAIR | 6 | 5.25 | 5 | 10 | 5 | 12 | 15 | 20 | 12 | 5 | 12 | 12 | 7.5 | 85 Ohms | TOP=L2:L3=L2/L4:L6=L5/L7:BOTTOM=L7 |
| D85_PCIE_B_TX0_N | D85_PCIE_B_TX0-DIFF1 | PAIR | 7 | 6.88 | 5 | 10 | 5 | 12 | 15 | 20 | 12 | 5 | 12 | 12 | 5.62 | 85 Ohms | TOP=L2:L3=L2/L4:L6=L5/L7:BOTTOM=L7 |
| D85_PCIE_B_TX0_N | D85_PCIE_B_TX0-DIFF1 | PAIR | 8 | 5.38 | 5 | 10 | 5 | 12 | 15 | 36 | 12 | 12 | 12 | 12 | 6.2 | 85 Ohms | TOP=L2:L3=L2/L4:L6=L5/L7:BOTTOM=L7 |
| D85_PCIE_B_TX0_P | D85_PCIE_B_TX0-DIFF1 | PAIR | 1 | 5.38 | 5 | 10 | 5 | 12 | 15 | 36 | 12 | 12 | 12 | 12 | 6.2 | 85 Ohms | TOP=L2:L3=L2/L4:L6=L5/L7:BOTTOM=L7 |
| D85_PCIE_B_TX0_P | D85_PCIE_B_TX0-DIFF1 | PAIR | 2 | 6.88 | 5 | 10 | 5 | 12 | 15 | 20 | 12 | 5 | 12 | 12 | 5.62 | 85 Ohms | TOP=L2:L3=L2/L4:L6=L5/L7:BOTTOM=L7 |
| D85_PCIE_B_TX0_P | D85_PCIE_B_TX0-DIFF1 | PAIR | 3 | 5.25 | 5 | 10 | 5 | 12 | 15 | 20 | 12 | 5 | 12 | 12 | 7.5 | 85 Ohms | TOP=L2:L3=L2/L4:L6=L5/L7:BOTTOM=L7 |
| D85_PCIE_B_TX0_P | D85_PCIE_B_TX0-DIFF1 | PAIR | 4 | 6.88 | 5 | 10 | 5 | 12 | 15 | 20 | 12 | 5 | 12 | 12 | 5.62 | 85 Ohms | TOP=L2:L3=L2/L4:L6=L5/L7:BOTTOM=L7 |
| D85_PCIE_B_TX0_P | D85_PCIE_B_TX0-DIFF1 | PAIR | 5 | 6.88 | 5 | 10 | 5 | 12 | 15 | 20 | 12 | 5 | 12 | 12 | 5.62 | 85 Ohms | TOP=L2:L3=L2/L4:L6=L5/L7:BOTTOM=L7 |
| D85_PCIE_B_TX0_P | D85_PCIE_B_TX0-DIFF1 | PAIR | 6 | 5.25 | 5 | 10 | 5 | 12 | 15 | 20 | 12 | 5 | 12 | 12 | 7.5 | 85 Ohms | TOP=L2:L3=L2/L4:L6=L5/L7:BOTTOM=L7 |
| D85_PCIE_B_TX0_P | D85_PCIE_B_TX0-DIFF1 | PAIR | 7 | 6.88 | 5 | 10 | 5 | 12 | 15 | 20 | 12 | 5 | 12 | 12 | 5.62 | 85 Ohms | TOP=L2:L3=L2/L4:L6=L5/L7:BOTTOM=L7 |
| D85_PCIE_B_TX0_P | D85_PCIE_B_TX0-DIFF1 | PAIR | 8 | 5.38 | 5 | 10 | 5 | 12 | 15 | 36 | 12 | 12 | 12 | 12 | 6.2 | 85 Ohms | TOP=L2:L3=L2/L4:L6=L5/L7:BOTTOM=L7 |
| D85_PCIE_B_TX1_N | D85_PCIE_B_TX1-DIFF1 | PAIR | 1 | 5.38 | 5 | 10 | 5 | 14 | 15 | 36 | 12 | 12 | 12 | 12 | 6.2 | 85 Ohms | TOP=L2:L3=L2/L4:L6=L5/L7:BOTTOM=L7 |
| D85_PCIE_B_TX1_N | D85_PCIE_B_TX1-DIFF1 | PAIR | 2 | 6.88 | 5 | 10 | 5 | 14 | 15 | 20 | 12 | 5 | 12 | 12 | 5.62 | 85 Ohms | TOP=L2:L3=L2/L4:L6=L5/L7:BOTTOM=L7 |
| D85_PCIE_B_TX1_N | D85_PCIE_B_TX1-DIFF1 | PAIR | 3 | 5.25 | 5 | 10 | 5 | 14 | 15 | 20 | 12 | 5 | 12 | 12 | 7.5 | 85 Ohms | TOP=L2:L3=L2/L4:L6=L5/L7:BOTTOM=L7 |
| D85_PCIE_B_TX1_N | D85_PCIE_B_TX1-DIFF1 | PAIR | 4 | 6.88 | 5 | 10 | 5 | 14 | 15 | 20 | 12 | 5 | 12 | 12 | 5.62 | 85 Ohms | TOP=L2:L3=L2/L4:L6=L5/L7:BOTTOM=L7 |
| D85_PCIE_B_TX1_N | D85_PCIE_B_TX1-DIFF1 | PAIR | 5 | 6.88 | 5 | 10 | 5 | 14 | 15 | 20 | 12 | 5 | 12 | 12 | 5.62 | 85 Ohms | TOP=L2:L3=L2/L4:L6=L5/L7:BOTTOM=L7 |
| D85_PCIE_B_TX1_N | D85_PCIE_B_TX1-DIFF1 | PAIR | 6 | 5.25 | 5 | 10 | 5 | 14 | 15 | 20 | 12 | 5 | 12 | 12 | 7.5 | 85 Ohms | TOP=L2:L3=L2/L4:L6=L5/L7:BOTTOM=L7 |
| D85_PCIE_B_TX1_N | D85_PCIE_B_TX1-DIFF1 | PAIR | 7 | 6.88 | 5 | 10 | 5 | 14 | 15 | 20 | 12 | 5 | 12 | 12 | 5.62 | 85 Ohms | TOP=L2:L3=L2/L4:L6=L5/L7:BOTTOM=L7 |
| D85_PCIE_B_TX1_N | D85_PCIE_B_TX1-DIFF1 | PAIR | 8 | 5.38 | 5 | 10 | 5 | 14 | 15 | 36 | 12 | 12 | 12 | 12 | 6.2 | 85 Ohms | TOP=L2:L3=L2/L4:L6=L5/L7:BOTTOM=L7 |
| D85_PCIE_B_TX1_P | D85_PCIE_B_TX1-DIFF1 | PAIR | 1 | 5.38 | 5 | 10 | 5 | 14 | 15 | 36 | 12 | 12 | 12 | 12 | 6.2 | 85 Ohms | TOP=L2:L3=L2/L4:L6=L5/L7:BOTTOM=L7 |
| D85_PCIE_B_TX1_P | D85_PCIE_B_TX1-DIFF1 | PAIR | 2 | 6.88 | 5 | 10 | 5 | 14 | 15 | 20 | 12 | 5 | 12 | 12 | 5.62 | 85 Ohms | TOP=L2:L3=L2/L4:L6=L5/L7:BOTTOM=L7 |
| D85_PCIE_B_TX1_P | D85_PCIE_B_TX1-DIFF1 | PAIR | 3 | 5.25 | 5 | 10 | 5 | 14 | 15 | 20 | 12 | 5 | 12 | 12 | 7.5 | 85 Ohms | TOP=L2:L3=L2/L4:L6=L5/L7:BOTTOM=L7 |
| D85_PCIE_B_TX1_P | D85_PCIE_B_TX1-DIFF1 | PAIR | 4 | 6.88 | 5 | 10 | 5 | 14 | 15 | 20 | 12 | 5 | 12 | 12 | 5.62 | 85 Ohms | TOP=L2:L3=L2/L4:L6=L5/L7:BOTTOM=L7 |
| D85_PCIE_B_TX1_P | D85_PCIE_B_TX1-DIFF1 | PAIR | 5 | 6.88 | 5 | 10 | 5 | 14 | 15 | 20 | 12 | 5 | 12 | 12 | 5.62 | 85 Ohms | TOP=L2:L3=L2/L4:L6=L5/L7:BOTTOM=L7 |
| D85_PCIE_B_TX1_P | D85_PCIE_B_TX1-DIFF1 | PAIR | 6 | 5.25 | 5 | 10 | 5 | 14 | 15 | 20 | 12 | 5 | 12 | 12 | 7.5 | 85 Ohms | TOP=L2:L3=L2/L4:L6=L5/L7:BOTTOM=L7 |
| D85_PCIE_B_TX1_P | D85_PCIE_B_TX1-DIFF1 | PAIR | 7 | 6.88 | 5 | 10 | 5 | 14 | 15 | 20 | 12 | 5 | 12 | 12 | 5.62 | 85 Ohms | TOP=L2:L3=L2/L4:L6=L5/L7:BOTTOM=L7 |
| D85_PCIE_B_TX1_P | D85_PCIE_B_TX1-DIFF1 | PAIR | 8 | 5.38 | 5 | 10 | 5 | 14 | 15 | 36 | 12 | 12 | 12 | 12 | 6.2 | 85 Ohms | TOP=L2:L3=L2/L4:L6=L5/L7:BOTTOM=L7 |
| AGND_P3V3_DEV | GND | PWR/GND | 1 | 200 | 5 | 10 | 5 | 14 | 6 | 15 | 12 | 12 | 12 | 12 |  |  |  |
| GND | GND | PWR/GND | 1 | 200 | 5 | 10 | 5 | 14 | 6 | 15 | 12 | 12 | 12 | 12 |  |  |  |
| P1V8_PWR_EN_R | POWER_10MIL | PWR/GND | 1 | 10 | 5 | 10 | 5 | 14 | 12 | 15 | 12 | 12 | 12 | 12 |  |  |  |
| P1V8_PWR_FB | POWER_10MIL | PWR/GND | 1 | 10 | 5 | 10 | 5 | 14 | 12 | 15 | 12 | 12 | 12 | 12 |  |  |  |
| P1V8_PWR_GD | POWER_10MIL | PWR/GND | 1 | 10 | 5 | 10 | 5 | 14 | 12 | 15 | 12 | 12 | 12 | 12 |  |  |  |
| P1V8_PWR_SS_C | POWER_10MIL | PWR/GND | 1 | 10 | 5 | 10 | 5 | 14 | 12 | 15 | 12 | 12 | 12 | 12 |  |  |  |
| P3V3_DEV_EN | POWER_10MIL | PWR/GND | 1 | 10 | 5 | 10 | 5 | 14 | 12 | 15 | 12 | 12 | 12 | 12 |  |  |  |
| P3V3_DEV_MODE | POWER_10MIL | PWR/GND | 1 | 10 | 5 | 10 | 5 | 14 | 12 | 15 | 12 | 12 | 12 | 12 |  |  |  |
| P3V3_DEV_PWRGD | POWER_10MIL | PWR/GND | 1 | 10 | 5 | 10 | 5 | 14 | 12 | 15 | 12 | 12 | 12 | 12 |  |  |  |
| P3V3_DEV_RF | POWER_10MIL | PWR/GND | 1 | 10 | 5 | 10 | 5 | 14 | 12 | 15 | 12 | 12 | 12 | 12 |  |  |  |
| P3V3_DEV_TRIP | POWER_10MIL | PWR/GND | 1 | 10 | 5 | 10 | 5 | 14 | 12 | 15 | 12 | 12 | 12 | 12 |  |  |  |
| P3V3_DEV_VFB | POWER_10MIL | PWR/GND | 1 | 10 | 5 | 10 | 5 | 14 | 12 | 15 | 12 | 12 | 12 | 12 |  |  |  |
| P3V3_DEV_VFB_R | POWER_10MIL | PWR/GND | 1 | 10 | 5 | 10 | 5 | 14 | 12 | 15 | 12 | 12 | 12 | 12 |  |  |  |
| P3V3_DEV_ROVP | POWER_10MIL_NO_TP | PWR/GND | 1 | 10 | 5 | 10 | 5 | 14 | 12 | 15 | 12 | 12 | 12 | 12 |  |  |  |
| P12V | POWER_120MIL | PWR/GND | 1 | 120 | 5 | 10 | 5 | 14 | 12 | 15 | 12 | 12 | 12 | 12 |  |  |  |
| P3V3_DEV_VIN | POWER_120MIL | PWR/GND | 1 | 120 | 5 | 10 | 5 | 14 | 12 | 15 | 12 | 12 | 12 | 12 |  |  |  |
| P1V8_PWR | POWER_20MIL | PWR/GND | 1 | 20 | 5 | 10 | 5 | 14 | 12 | 15 | 12 | 12 | 12 | 12 |  |  |  |
| P1V8_PWR_BIAS | POWER_20MIL | PWR/GND | 1 | 20 | 5 | 10 | 5 | 14 | 12 | 15 | 12 | 12 | 12 | 12 |  |  |  |
| P3V3_DEV_VDD | POWER_20MIL | PWR/GND | 1 | 20 | 5 | 10 | 5 | 14 | 12 | 15 | 12 | 12 | 12 | 12 |  |  |  |
| P3V3_DPB | POWER_20MIL | PWR/GND | 1 | 20 | 5 | 10 | 5 | 14 | 12 | 15 | 12 | 12 | 12 | 12 |  |  |  |
| P3V3_DEV_VREG | POWER_20MIL_18S | PWR/GND | 1 | 20 | 5 | 10 | 5 | 14 | 12 | 18 | 12 | 12 | 12 | 12 |  |  |  |
| P3V3_PWR | POWER_360MIL | PWR/GND | 1 | 360 | 5 | 10 | 5 | 14 | 12 | 15 | 12 | 12 | 12 | 12 |  |  |  |
| P3V3_DEV_LL | POWER_NOISY_20MIL | PWR/GND | 1 | 20 | 5 | 10 | 5 | 50 | 50 | 50 | 12 | 12 | 30 | 12 |  |  |  |
| P3V3_DEV_LL_R | POWER_NOISY_20MIL | PWR/GND | 1 | 20 | 5 | 10 | 5 | 50 | 50 | 50 | 12 | 12 | 30 | 12 |  |  |  |
| P3V3_DEV_SNB | POWER_NOISY_20MIL | PWR/GND | 1 | 20 | 5 | 10 | 5 | 50 | 50 | 50 | 12 | 12 | 30 | 12 |  |  |  |
| P3V3_DEV_VBST | POWER_NOISY_20MIL | PWR/GND | 1 | 20 | 5 | 10 | 5 | 50 | 50 | 50 | 12 | 12 | 30 | 12 |  |  |  |
| P3V3_DEV_VBST_RC | POWER_NOISY_20MIL | PWR/GND | 1 | 20 | 5 | 10 | 5 | 50 | 50 | 50 | 12 | 12 | 30 | 12 |  |  |  |
